(kicad_pcb
	(version 20260206)
	(generator "pcbnew")
	(generator_version "10.0")
	(general
		(thickness 1.6)
		(legacy_teardrops no)
	)
	(paper "A4")
	(title_block
		(title "Bryce Canyon_SCC_16316-1_OCP.brd")
		(comment 1 "Bryce Canyon / footprints 817-823 of 1561")
	)
	(layers
		(0 "F.Cu" signal "TOP")
		(4 "In1.Cu" signal "L2GND")
		(6 "In2.Cu" signal "L3")
		(8 "In3.Cu" signal "L4VCC")
		(10 "In4.Cu" signal "L5VCC")
		(12 "In5.Cu" signal "L6")
		(14 "In6.Cu" signal "L7GND")
		(2 "B.Cu" signal "BOTTOM")
		(9 "F.Adhes" user "F.Adhesive")
		(11 "B.Adhes" user "B.Adhesive")
		(13 "F.Paste" user "Package Geometry/Pastemask Top")
		(15 "B.Paste" user "Package Geometry/Pastemask Bottom")
		(5 "F.SilkS" user "Ref Des/Silkscreen Top")
		(7 "B.SilkS" user "Ref Des/Silkscreen Bottom")
		(1 "F.Mask" user "Board Geometry/Soldermask Top")
		(3 "B.Mask" user "Board Geometry/Soldermask Bottom")
		(17 "Dwgs.User" user "User.Drawings")
		(19 "Cmts.User" user "User.Comments")
		(21 "Eco1.User" user "User.Eco1")
		(23 "Eco2.User" user "User.Eco2")
		(25 "Edge.Cuts" user "Board Geometry/Outline")
		(27 "Margin" user)
		(31 "F.CrtYd" user "Package Geometry/Place Bound Top")
		(29 "B.CrtYd" user "Package Geometry/Place Bound Bottom")
		(35 "F.Fab" user "Ref Des/Assembly Top")
		(33 "B.Fab" user "Ref Des/Assembly Bottom")
	)
	(footprint ""
		(layer "B.Cu")
		(at 179.430934 -39.730426 90)
		(property "Reference" "C424"
			(at 0 0 90)
			(layer "B.SilkS")
			(hide yes)
			(effects
				(font
					(size 1.27 1.27)
				)
				(justify mirror)
			)
		)
		(property "Value" "SCD1U6D3V1KX-GP"
			(at 2.8321 -1.7399 90)
			(unlocked yes)
			(layer "B.Fab")
			(hide yes)
			(effects
				(font
					(size 1.016 1.016)
					(thickness 0.1524)
				)
				(justify mirror)
			)
		)
		(property "Device Type" "C0201H13"
			(at 2.8321 -3.2639 90)
			(unlocked yes)
			(layer "B.Fab")
			(hide yes)
			(effects
				(font
					(size 1.016 1.016)
					(thickness 0.1524)
				)
				(justify mirror)
			)
		)
		(duplicate_pad_numbers_are_jumpers no)
		(fp_rect
			(start 0.2794 0.6477)
			(end -0.2794 -0.6477)
			(stroke
				(width 0)
				(type default)
			)
			(fill no)
			(layer "B.CrtYd")
		)
		(fp_rect
			(start 0.2794 0.6477)
			(end -0.2794 -0.6477)
			(stroke
				(width 0)
				(type default)
			)
			(fill no)
			(layer "B.Fab")
		)
		(pad "1" smd custom
			(at 0 -0.2794 270)
			(size 0.0762 0.0762)
			(layers "B.Cu" "B.Mask" "B.Paste")
			(net "P0V975")
			(options
				(clearance outline)
				(anchor circle)
			)
			(primitives
				(gr_poly
					(pts
						(arc
							(start 0.1524 0.127)
							(mid 0.137521 0.162921)
							(end 0.1016 0.1778)
						)
						(arc
							(start -0.1016 0.1778)
							(mid -0.137521 0.162921)
							(end -0.1524 0.127)
						)
						(arc
							(start -0.1524 -0.127)
							(mid -0.137521 -0.162921)
							(end -0.1016 -0.1778)
						)
						(arc
							(start 0.1016 -0.1778)
							(mid 0.137521 -0.162921)
							(end 0.1524 -0.127)
						)
					)
					(width 0)
					(fill yes)
				)
			)
		)
		(pad "2" smd custom
			(at 0 0.2794 270)
			(size 0.0762 0.0762)
			(layers "B.Cu" "B.Mask" "B.Paste")
			(net "GND")
			(options
				(clearance outline)
				(anchor circle)
			)
			(primitives
				(gr_poly
					(pts
						(arc
							(start 0.1524 0.127)
							(mid 0.137521 0.162921)
							(end 0.1016 0.1778)
						)
						(arc
							(start -0.1016 0.1778)
							(mid -0.137521 0.162921)
							(end -0.1524 0.127)
						)
						(arc
							(start -0.1524 -0.127)
							(mid -0.137521 -0.162921)
							(end -0.1016 -0.1778)
						)
						(arc
							(start 0.1016 -0.1778)
							(mid 0.137521 -0.162921)
							(end 0.1524 -0.127)
						)
					)
					(width 0)
					(fill yes)
				)
			)
		)
	)
	(footprint ""
		(layer "B.Cu")
		(at 107.270042 -72.605392)
		(property "Reference" "C119"
			(at 0 0 0)
			(layer "B.SilkS")
			(hide yes)
			(effects
				(font
					(size 1.27 1.27)
				)
				(justify mirror)
			)
		)
		(property "Value" "SC10U6D3V2MX-GP-U"
			(at 1.524 -1.905 0)
			(unlocked yes)
			(layer "B.Fab")
			(hide yes)
			(effects
				(font
					(size 1.016 1.016)
					(thickness 0.1524)
				)
				(justify mirror)
			)
		)
		(property "Device Type" "C402-TO0D2H28"
			(at 1.524 -3.429 0)
			(unlocked yes)
			(layer "B.Fab")
			(hide yes)
			(effects
				(font
					(size 1.016 1.016)
					(thickness 0.1524)
				)
				(justify mirror)
			)
		)
		(duplicate_pad_numbers_are_jumpers no)
		(fp_rect
			(start 0.4826 0.889)
			(end -0.4826 -0.889)
			(stroke
				(width 0)
				(type default)
			)
			(fill no)
			(layer "B.CrtYd")
		)
		(fp_rect
			(start 0.4826 0.889)
			(end -0.4826 -0.889)
			(stroke
				(width 0)
				(type default)
			)
			(fill no)
			(layer "B.Fab")
		)
		(pad "1" smd custom
			(at 0 -0.4572 180)
			(size 0.1524 0.1524)
			(layers "B.Cu" "B.Mask" "B.Paste")
			(net "P1V8_E")
			(options
				(clearance outline)
				(anchor circle)
			)
			(primitives
				(gr_poly
					(pts
						(arc
							(start -0.254 -0.3048)
							(mid -0.325842 -0.275042)
							(end -0.3556 -0.2032)
						)
						(arc
							(start -0.3556 0.2032)
							(mid -0.325842 0.275042)
							(end -0.254 0.3048)
						)
						(arc
							(start 0.254 0.3048)
							(mid 0.325842 0.275042)
							(end 0.3556 0.2032)
						)
						(arc
							(start 0.3556 -0.2032)
							(mid 0.325842 -0.275042)
							(end 0.254 -0.3048)
						)
					)
					(width 0)
					(fill yes)
				)
			)
		)
		(pad "2" smd custom
			(at 0 0.4572 180)
			(size 0.1524 0.1524)
			(layers "B.Cu" "B.Mask" "B.Paste")
			(net "GND")
			(options
				(clearance outline)
				(anchor circle)
			)
			(primitives
				(gr_poly
					(pts
						(arc
							(start -0.254 -0.3048)
							(mid -0.325842 -0.275042)
							(end -0.3556 -0.2032)
						)
						(arc
							(start -0.3556 0.2032)
							(mid -0.325842 0.275042)
							(end -0.254 0.3048)
						)
						(arc
							(start 0.254 0.3048)
							(mid 0.325842 0.275042)
							(end 0.3556 0.2032)
						)
						(arc
							(start 0.3556 -0.2032)
							(mid 0.325842 -0.275042)
							(end 0.254 -0.3048)
						)
					)
					(width 0)
					(fill yes)
				)
			)
		)
	)
	(footprint ""
		(layer "B.Cu")
		(at 128.366266 -87.251794)
		(property "Reference" "R301"
			(at 0 0 0)
			(layer "B.SilkS")
			(hide yes)
			(effects
				(font
					(size 1.27 1.27)
				)
				(justify mirror)
			)
		)
		(property "Value" "4K75R2F-1-GP"
			(at -0.064008 -3.993896 0)
			(unlocked yes)
			(layer "B.Fab")
			(hide yes)
			(effects
				(font
					(size 1.016 1.016)
					(thickness 0.1524)
				)
				(justify mirror)
			)
		)
		(property "Device Type" "R402H16"
			(at -0.064008 -5.517896 0)
			(unlocked yes)
			(layer "B.Fab")
			(hide yes)
			(effects
				(font
					(size 1.016 1.016)
					(thickness 0.1524)
				)
				(justify mirror)
			)
		)
		(duplicate_pad_numbers_are_jumpers no)
		(fp_line
			(start -0.508 -0.9398)
			(end 0.508 -0.9398)
			(stroke
				(width 0.1524)
				(type default)
			)
			(layer "B.SilkS")
		)
		(fp_line
			(start 0.508 -0.9398)
			(end 0.508 0.9398)
			(stroke
				(width 0.1524)
				(type default)
			)
			(layer "B.SilkS")
		)
		(fp_rect
			(start 0.508 0.9398)
			(end -0.508 -0.9398)
			(stroke
				(width 0)
				(type default)
			)
			(fill no)
			(layer "B.CrtYd")
		)
		(fp_rect
			(start 0.508 0.9398)
			(end -0.508 -0.9398)
			(stroke
				(width 0)
				(type default)
			)
			(fill no)
			(layer "B.Fab")
		)
		(pad "1" smd custom
			(at 0 -0.4445 180)
			(size 0.1397 0.1397)
			(layers "B.Cu" "B.Mask" "B.Paste")
			(net "P1V8_E")
			(options
				(clearance outline)
				(anchor circle)
			)
			(primitives
				(gr_poly
					(pts
						(arc
							(start -0.1778 0.2794)
							(mid -0.249642 0.249642)
							(end -0.2794 0.1778)
						)
						(arc
							(start -0.2794 -0.1778)
							(mid -0.249642 -0.249642)
							(end -0.1778 -0.2794)
						)
						(arc
							(start 0.1778 -0.2794)
							(mid 0.249642 -0.249642)
							(end 0.2794 -0.1778)
						)
						(arc
							(start 0.2794 0.1778)
							(mid 0.249642 0.249642)
							(end 0.1778 0.2794)
						)
					)
					(width 0)
					(fill yes)
				)
			)
		)
		(pad "2" smd custom
			(at 0 0.4445 180)
			(size 0.1397 0.1397)
			(layers "B.Cu" "B.Mask" "B.Paste")
			(net "ICE_TDI")
			(options
				(clearance outline)
				(anchor circle)
			)
			(primitives
				(gr_poly
					(pts
						(arc
							(start -0.1778 0.2794)
							(mid -0.249642 0.249642)
							(end -0.2794 0.1778)
						)
						(arc
							(start -0.2794 -0.1778)
							(mid -0.249642 -0.249642)
							(end -0.1778 -0.2794)
						)
						(arc
							(start 0.1778 -0.2794)
							(mid 0.249642 -0.249642)
							(end 0.2794 -0.1778)
						)
						(arc
							(start 0.2794 0.1778)
							(mid 0.249642 0.249642)
							(end 0.1778 0.2794)
						)
					)
					(width 0)
					(fill yes)
				)
			)
		)
	)
	(footprint ""
		(layer "B.Cu")
		(at 174.405544 -34.123884 180)
		(property "Reference" "C388"
			(at 0 0 0)
			(layer "B.SilkS")
			(hide yes)
			(effects
				(font
					(size 1.27 1.27)
				)
				(justify mirror)
			)
		)
		(property "Value" "SCD1U6D3V1KX-GP"
			(at 2.8321 -1.7399 180)
			(unlocked yes)
			(layer "B.Fab")
			(hide yes)
			(effects
				(font
					(size 1.016 1.016)
					(thickness 0.1524)
				)
				(justify mirror)
			)
		)
		(property "Device Type" "C0201H13"
			(at 2.8321 -3.2639 180)
			(unlocked yes)
			(layer "B.Fab")
			(hide yes)
			(effects
				(font
					(size 1.016 1.016)
					(thickness 0.1524)
				)
				(justify mirror)
			)
		)
		(duplicate_pad_numbers_are_jumpers no)
		(fp_rect
			(start 0.2794 0.6477)
			(end -0.2794 -0.6477)
			(stroke
				(width 0)
				(type default)
			)
			(fill no)
			(layer "B.CrtYd")
		)
		(fp_rect
			(start 0.2794 0.6477)
			(end -0.2794 -0.6477)
			(stroke
				(width 0)
				(type default)
			)
			(fill no)
			(layer "B.Fab")
		)
		(pad "1" smd custom
			(at 0 -0.2794)
			(size 0.0762 0.0762)
			(layers "B.Cu" "B.Mask" "B.Paste")
			(net "PCE_AVDD")
			(options
				(clearance outline)
				(anchor circle)
			)
			(primitives
				(gr_poly
					(pts
						(arc
							(start 0.1524 0.127)
							(mid 0.137521 0.162921)
							(end 0.1016 0.1778)
						)
						(arc
							(start -0.1016 0.1778)
							(mid -0.137521 0.162921)
							(end -0.1524 0.127)
						)
						(arc
							(start -0.1524 -0.127)
							(mid -0.137521 -0.162921)
							(end -0.1016 -0.1778)
						)
						(arc
							(start 0.1016 -0.1778)
							(mid 0.137521 -0.162921)
							(end 0.1524 -0.127)
						)
					)
					(width 0)
					(fill yes)
				)
			)
		)
		(pad "2" smd custom
			(at 0 0.2794)
			(size 0.0762 0.0762)
			(layers "B.Cu" "B.Mask" "B.Paste")
			(net "GND")
			(options
				(clearance outline)
				(anchor circle)
			)
			(primitives
				(gr_poly
					(pts
						(arc
							(start 0.1524 0.127)
							(mid 0.137521 0.162921)
							(end 0.1016 0.1778)
						)
						(arc
							(start -0.1016 0.1778)
							(mid -0.137521 0.162921)
							(end -0.1524 0.127)
						)
						(arc
							(start -0.1524 -0.127)
							(mid -0.137521 -0.162921)
							(end -0.1016 -0.1778)
						)
						(arc
							(start 0.1016 -0.1778)
							(mid 0.137521 -0.162921)
							(end 0.1524 -0.127)
						)
					)
					(width 0)
					(fill yes)
				)
			)
		)
	)
	(footprint ""
		(layer "B.Cu")
		(at 179.40909 -48.203358 -90)
		(property "Reference" "C492"
			(at 0 0 90)
			(layer "B.SilkS")
			(hide yes)
			(effects
				(font
					(size 1.27 1.27)
				)
				(justify mirror)
			)
		)
		(property "Value" "SCD1U6D3V1KX-GP"
			(at 2.8321 -1.7399 270)
			(unlocked yes)
			(layer "B.Fab")
			(hide yes)
			(effects
				(font
					(size 1.016 1.016)
					(thickness 0.1524)
				)
				(justify mirror)
			)
		)
		(property "Device Type" "C0201H13"
			(at 2.8321 -3.2639 270)
			(unlocked yes)
			(layer "B.Fab")
			(hide yes)
			(effects
				(font
					(size 1.016 1.016)
					(thickness 0.1524)
				)
				(justify mirror)
			)
		)
		(duplicate_pad_numbers_are_jumpers no)
		(fp_rect
			(start 0.2794 0.6477)
			(end -0.2794 -0.6477)
			(stroke
				(width 0)
				(type default)
			)
			(fill no)
			(layer "B.CrtYd")
		)
		(fp_rect
			(start 0.2794 0.6477)
			(end -0.2794 -0.6477)
			(stroke
				(width 0)
				(type default)
			)
			(fill no)
			(layer "B.Fab")
		)
		(pad "1" smd custom
			(at 0 -0.2794 90)
			(size 0.0762 0.0762)
			(layers "B.Cu" "B.Mask" "B.Paste")
			(net "P1V8_C")
			(options
				(clearance outline)
				(anchor circle)
			)
			(primitives
				(gr_poly
					(pts
						(arc
							(start 0.1524 0.127)
							(mid 0.137521 0.162921)
							(end 0.1016 0.1778)
						)
						(arc
							(start -0.1016 0.1778)
							(mid -0.137521 0.162921)
							(end -0.1524 0.127)
						)
						(arc
							(start -0.1524 -0.127)
							(mid -0.137521 -0.162921)
							(end -0.1016 -0.1778)
						)
						(arc
							(start 0.1016 -0.1778)
							(mid 0.137521 -0.162921)
							(end 0.1524 -0.127)
						)
					)
					(width 0)
					(fill yes)
				)
			)
		)
		(pad "2" smd custom
			(at 0 0.2794 90)
			(size 0.0762 0.0762)
			(layers "B.Cu" "B.Mask" "B.Paste")
			(net "GND")
			(options
				(clearance outline)
				(anchor circle)
			)
			(primitives
				(gr_poly
					(pts
						(arc
							(start 0.1524 0.127)
							(mid 0.137521 0.162921)
							(end 0.1016 0.1778)
						)
						(arc
							(start -0.1016 0.1778)
							(mid -0.137521 0.162921)
							(end -0.1524 0.127)
						)
						(arc
							(start -0.1524 -0.127)
							(mid -0.137521 -0.162921)
							(end -0.1016 -0.1778)
						)
						(arc
							(start 0.1016 -0.1778)
							(mid 0.137521 -0.162921)
							(end 0.1524 -0.127)
						)
					)
					(width 0)
					(fill yes)
				)
			)
		)
	)
	(footprint ""
		(layer "B.Cu")
		(at 191.897 -43.053 -90)
		(property "Reference" "R188"
			(at 0 0 90)
			(layer "B.SilkS")
			(hide yes)
			(effects
				(font
					(size 1.27 1.27)
				)
				(justify mirror)
			)
		)
		(property "Value" "2K2R2F-GP"
			(at -0.064008 -3.993896 270)
			(unlocked yes)
			(layer "B.Fab")
			(hide yes)
			(effects
				(font
					(size 1.016 1.016)
					(thickness 0.1524)
				)
				(justify mirror)
			)
		)
		(property "Device Type" "R402H16"
			(at -0.064008 -5.517896 270)
			(unlocked yes)
			(layer "B.Fab")
			(hide yes)
			(effects
				(font
					(size 1.016 1.016)
					(thickness 0.1524)
				)
				(justify mirror)
			)
		)
		(duplicate_pad_numbers_are_jumpers no)
		(fp_line
			(start -0.508 -0.9398)
			(end 0.508 -0.9398)
			(stroke
				(width 0.1524)
				(type default)
			)
			(layer "B.SilkS")
		)
		(fp_line
			(start 0.508 -0.9398)
			(end 0.508 0.9398)
			(stroke
				(width 0.1524)
				(type default)
			)
			(layer "B.SilkS")
		)
		(fp_rect
			(start 0.508 0.9398)
			(end -0.508 -0.9398)
			(stroke
				(width 0)
				(type default)
			)
			(fill no)
			(layer "B.CrtYd")
		)
		(fp_rect
			(start 0.508 0.9398)
			(end -0.508 -0.9398)
			(stroke
				(width 0)
				(type default)
			)
			(fill no)
			(layer "B.Fab")
		)
		(pad "1" smd custom
			(at 0 -0.4445 90)
			(size 0.1397 0.1397)
			(layers "B.Cu" "B.Mask" "B.Paste")
			(net "P1V8_C")
			(options
				(clearance outline)
				(anchor circle)
			)
			(primitives
				(gr_poly
					(pts
						(arc
							(start -0.1778 0.2794)
							(mid -0.249642 0.249642)
							(end -0.2794 0.1778)
						)
						(arc
							(start -0.2794 -0.1778)
							(mid -0.249642 -0.249642)
							(end -0.1778 -0.2794)
						)
						(arc
							(start 0.1778 -0.2794)
							(mid 0.249642 -0.249642)
							(end 0.2794 -0.1778)
						)
						(arc
							(start 0.2794 0.1778)
							(mid 0.249642 0.249642)
							(end 0.1778 0.2794)
						)
					)
					(width 0)
					(fill yes)
				)
			)
		)
		(pad "2" smd custom
			(at 0 0.4445 90)
			(size 0.1397 0.1397)
			(layers "B.Cu" "B.Mask" "B.Paste")
			(net "I2C_IOC_3_SCL")
			(options
				(clearance outline)
				(anchor circle)
			)
			(primitives
				(gr_poly
					(pts
						(arc
							(start -0.1778 0.2794)
							(mid -0.249642 0.249642)
							(end -0.2794 0.1778)
						)
						(arc
							(start -0.2794 -0.1778)
							(mid -0.249642 -0.249642)
							(end -0.1778 -0.2794)
						)
						(arc
							(start 0.1778 -0.2794)
							(mid 0.249642 -0.249642)
							(end 0.2794 -0.1778)
						)
						(arc
							(start 0.2794 0.1778)
							(mid 0.249642 0.249642)
							(end 0.1778 0.2794)
						)
					)
					(width 0)
					(fill yes)
				)
			)
		)
	)
	(footprint ""
		(layer "B.Cu")
		(at 160.6042 -39.7256 180)
		(property "Reference" "R240"
			(at 0 0 0)
			(layer "B.SilkS")
			(hide yes)
			(effects
				(font
					(size 1.27 1.27)
				)
				(justify mirror)
			)
		)
		(property "Value" "3KR2J-2-GP"
			(at -0.064008 -3.993896 180)
			(unlocked yes)
			(layer "B.Fab")
			(hide yes)
			(effects
				(font
					(size 1.016 1.016)
					(thickness 0.1524)
				)
				(justify mirror)
			)
		)
		(property "Device Type" "R402H16"
			(at -0.064008 -5.517896 180)
			(unlocked yes)
			(layer "B.Fab")
			(hide yes)
			(effects
				(font
					(size 1.016 1.016)
					(thickness 0.1524)
				)
				(justify mirror)
			)
		)
		(duplicate_pad_numbers_are_jumpers no)
		(fp_line
			(start 0.508 -0.9398)
			(end 0.508 0.9398)
			(stroke
				(width 0.1524)
				(type default)
			)
			(layer "B.SilkS")
		)
		(fp_line
			(start -0.508 -0.9398)
			(end 0.508 -0.9398)
			(stroke
				(width 0.1524)
				(type default)
			)
			(layer "B.SilkS")
		)
		(fp_rect
			(start 0.508 0.9398)
			(end -0.508 -0.9398)
			(stroke
				(width 0)
				(type default)
			)
			(fill no)
			(layer "B.CrtYd")
		)
		(fp_rect
			(start 0.508 0.9398)
			(end -0.508 -0.9398)
			(stroke
				(width 0)
				(type default)
			)
			(fill no)
			(layer "B.Fab")
		)
		(pad "1" smd custom
			(at 0 -0.4445)
			(size 0.1397 0.1397)
			(layers "B.Cu" "B.Mask" "B.Paste")
			(net "RTRIM")
			(options
				(clearance outline)
				(anchor circle)
			)
			(primitives
				(gr_poly
					(pts
						(arc
							(start -0.1778 0.2794)
							(mid -0.249642 0.249642)
							(end -0.2794 0.1778)
						)
						(arc
							(start -0.2794 -0.1778)
							(mid -0.249642 -0.249642)
							(end -0.1778 -0.2794)
						)
						(arc
							(start 0.1778 -0.2794)
							(mid 0.249642 -0.249642)
							(end 0.2794 -0.1778)
						)
						(arc
							(start 0.2794 0.1778)
							(mid 0.249642 0.249642)
							(end 0.1778 0.2794)
						)
					)
					(width 0)
					(fill yes)
				)
			)
		)
		(pad "2" smd custom
			(at 0 0.4445)
			(size 0.1397 0.1397)
			(layers "B.Cu" "B.Mask" "B.Paste")
			(net "RTRIM#")
			(options
				(clearance outline)
				(anchor circle)
			)
			(primitives
				(gr_poly
					(pts
						(arc
							(start -0.1778 0.2794)
							(mid -0.249642 0.249642)
							(end -0.2794 0.1778)
						)
						(arc
							(start -0.2794 -0.1778)
							(mid -0.249642 -0.249642)
							(end -0.1778 -0.2794)
						)
						(arc
							(start 0.1778 -0.2794)
							(mid 0.249642 -0.249642)
							(end 0.2794 -0.1778)
						)
						(arc
							(start 0.2794 0.1778)
							(mid 0.249642 0.249642)
							(end 0.1778 0.2794)
						)
					)
					(width 0)
					(fill yes)
				)
			)
		)
	)
)
